(kicad_pcb
	(version 20260206)
	(generator "pcbnew")
	(generator_version "10.0")
	(general
		(thickness 1.6)
		(legacy_teardrops no)
	)
	(paper "A4")
	(title_block
		(title "Bryce Canyon_F.DPB_16315-1-OCP.brd")
		(comment 1 "Bryce Canyon / footprints 1021-1024 of 2223")
	)
	(layers
		(0 "F.Cu" signal "TOP")
		(4 "In1.Cu" signal "L2GND")
		(6 "In2.Cu" signal "L3")
		(8 "In3.Cu" signal "L4GND")
		(10 "In4.Cu" signal "L5")
		(12 "In5.Cu" signal "L6VCC")
		(14 "In6.Cu" signal "L7VCC")
		(16 "In7.Cu" signal "L8")
		(18 "In8.Cu" signal "L9GND")
		(20 "In9.Cu" signal "L10")
		(22 "In10.Cu" signal "L11GND")
		(2 "B.Cu" signal "BOTTOM")
		(9 "F.Adhes" user "F.Adhesive")
		(11 "B.Adhes" user "B.Adhesive")
		(13 "F.Paste" user "Package Geometry/Pastemask Top")
		(15 "B.Paste" user "Package Geometry/Pastemask Bottom")
		(5 "F.SilkS" user "Ref Des/Silkscreen Top")
		(7 "B.SilkS" user "Ref Des/Silkscreen Bottom")
		(1 "F.Mask" user "Board Geometry/Soldermask Top")
		(3 "B.Mask" user "Board Geometry/Soldermask Bottom")
		(17 "Dwgs.User" user "User.Drawings")
		(19 "Cmts.User" user "User.Comments")
		(21 "Eco1.User" user "User.Eco1")
		(23 "Eco2.User" user "User.Eco2")
		(25 "Edge.Cuts" user "Board Geometry/Outline")
		(27 "Margin" user)
		(31 "F.CrtYd" user "Package Geometry/Place Bound Top")
		(29 "B.CrtYd" user "Package Geometry/Place Bound Bottom")
		(35 "F.Fab" user "Ref Des/Assembly Top")
		(33 "B.Fab" user "Ref Des/Assembly Bottom")
	)
	(footprint ""
		(layer "F.Cu")
		(at 91.300046 -57.909968 -90)
		(property "Reference" "HDDSAS26"
			(at 0 0 270)
			(layer "F.SilkS")
			(hide yes)
			(effects
				(font
					(size 1.27 1.27)
				)
			)
		)
		(property "Value" "SKT-SAS15P-14P-45-GP"
			(at -20.7645 -8.9789 270)
			(unlocked yes)
			(layer "F.Fab")
			(hide yes)
			(effects
				(font
					(size 1.016 1.016)
					(thickness 0.1524)
				)
			)
		)
		(property "Device Type" "10120818-001C-TRLF"
			(at -20.7645 -10.5029 270)
			(unlocked yes)
			(layer "F.Fab")
			(hide yes)
			(effects
				(font
					(size 1.016 1.016)
					(thickness 0.1524)
				)
			)
		)
		(duplicate_pad_numbers_are_jumpers no)
		(fp_line
			(start 1.651 4.2926)
			(end 1.651 3.0099)
			(stroke
				(width 0.1524)
				(type default)
			)
			(layer "F.SilkS")
		)
		(fp_line
			(start 8.509 4.2926)
			(end 1.651 4.2926)
			(stroke
				(width 0.1524)
				(type default)
			)
			(layer "F.SilkS")
		)
		(fp_line
			(start -23.4188 3.0099)
			(end -23.4188 -3.2512)
			(stroke
				(width 0.1524)
				(type default)
			)
			(layer "F.SilkS")
		)
		(fp_line
			(start 1.651 3.0099)
			(end -23.4188 3.0099)
			(stroke
				(width 0.1524)
				(type default)
			)
			(layer "F.SilkS")
		)
		(fp_line
			(start 8.509 3.0099)
			(end 8.509 4.2926)
			(stroke
				(width 0.1524)
				(type default)
			)
			(layer "F.SilkS")
		)
		(fp_line
			(start 23.4188 3.0099)
			(end 8.509 3.0099)
			(stroke
				(width 0.1524)
				(type default)
			)
			(layer "F.SilkS")
		)
		(fp_line
			(start -23.4188 -3.2512)
			(end 23.4188 -3.2512)
			(stroke
				(width 0.1524)
				(type default)
			)
			(layer "F.SilkS")
		)
		(fp_line
			(start 23.4188 -3.2512)
			(end 23.4188 3.0099)
			(stroke
				(width 0.1524)
				(type default)
			)
			(layer "F.SilkS")
		)
		(fp_line
			(start 15.5067 -3.3401)
			(end 16.2687 -3.3401)
			(stroke
				(width 0.3302)
				(type default)
			)
			(layer "F.SilkS")
		)
		(fp_poly
			(pts
				(xy 15.868904 -3.230372) (xy 16.503904 -3.865372) (xy 15.233904 -3.865372)
			)
			(stroke
				(width 0)
				(type default)
			)
			(fill yes)
			(layer "F.SilkS")
		)
		(fp_poly
			(pts
				(xy -22.8727 -2.7559) (xy 22.8727 -2.7559) (xy 22.8727 2.7559) (xy 8.255 2.7559) (xy 8.255 3.5179)
				(xy 1.905 3.5179) (xy 1.905 2.7559) (xy -22.8727 2.7559)
			)
			(stroke
				(width 0)
				(type default)
			)
			(fill no)
			(layer "F.CrtYd")
		)
		(fp_poly
			(pts
				(xy 1.397 4.5466) (xy 1.397 3.2639) (xy -23.6728 3.2639) (xy -23.6728 -3.5052) (xy 23.6728 -3.5052)
				(xy 23.6728 -0.00635) (xy 22.8727 -0.00635) (xy 22.8727 -2.7559) (xy -22.8727 -2.7559) (xy -22.8727 2.7559)
				(xy 1.905 2.7559) (xy 1.905 3.5179) (xy 8.255 3.5179) (xy 8.255 2.7559) (xy 22.8727 2.7559) (xy 22.8727 0.00635)
				(xy 23.6728 0.00635) (xy 23.6728 3.2639) (xy 8.763 3.2639) (xy 8.763 4.5466)
			)
			(stroke
				(width 0)
				(type default)
			)
			(fill no)
			(layer "F.CrtYd")
		)
		(fp_poly
			(pts
				(xy 1.397 4.5466) (xy 1.397 3.2639) (xy -23.6728 3.2639) (xy -23.6728 -3.5052) (xy 23.6728 -3.5052)
				(xy 23.6728 3.2639) (xy 8.763 3.2639) (xy 8.763 4.5466)
			)
			(stroke
				(width 0)
				(type default)
			)
			(fill no)
			(layer "F.Fab")
		)
		(pad "" np_thru_hole circle
			(at -18.874994 0 270)
			(size 0.254 0.254)
			(drill 1.3462)
			(layers "*.Cu" "*.Mask")
			(clearance 0.9017)
			(thermal_gap 0.9017)
		)
		(pad "" np_thru_hole circle
			(at 18.874994 0 270)
			(size 0.254 0.254)
			(drill 0.9398)
			(layers "*.Cu" "*.Mask")
			(clearance 0.6985)
			(thermal_gap 0.6985)
		)
		(pad "G1" smd rect
			(at 21.874988 0 270)
			(size 2.5908 2.5908)
			(layers "F.Cu" "F.Mask" "F.Paste")
			(net "GND")
		)
		(pad "G2" smd rect
			(at -21.874988 0 270)
			(size 2.5908 2.5908)
			(layers "F.Cu" "F.Mask" "F.Paste")
			(net "GND")
		)
		(pad "P1" smd rect
			(at 1.905 -1.82499 270)
			(size 0.6096 2.3622)
			(layers "F.Cu" "F.Mask" "F.Paste")
			(net "Net_2081")
		)
		(pad "P2" smd rect
			(at 0.635 -1.82499 270)
			(size 0.6096 2.3622)
			(layers "F.Cu" "F.Mask" "F.Paste")
			(net "Net_2082")
		)
		(pad "P3" smd rect
			(at -0.635 -1.82499 270)
			(size 0.6096 2.3622)
			(layers "F.Cu" "F.Mask" "F.Paste")
			(net "Net_2083")
		)
		(pad "P4" smd rect
			(at -1.905 -1.82499 270)
			(size 0.6096 2.3622)
			(layers "F.Cu" "F.Mask" "F.Paste")
			(net "GND")
		)
		(pad "P5" smd rect
			(at -3.175 -1.82499 270)
			(size 0.6096 2.3622)
			(layers "F.Cu" "F.Mask" "F.Paste")
			(net "HDD_PRSNT_26")
		)
		(pad "P6" smd rect
			(at -4.445 -1.82499 270)
			(size 0.6096 2.3622)
			(layers "F.Cu" "F.Mask" "F.Paste")
			(net "GND")
		)
		(pad "P7" smd rect
			(at -5.715 -1.82499 270)
			(size 0.6096 2.3622)
			(layers "F.Cu" "F.Mask" "F.Paste")
			(net "5V_PRE_26")
		)
		(pad "P8" smd rect
			(at -6.985 -1.82499 270)
			(size 0.6096 2.3622)
			(layers "F.Cu" "F.Mask" "F.Paste")
			(net "P5V_HDD26")
		)
		(pad "P9" smd rect
			(at -8.255 -1.82499 270)
			(size 0.6096 2.3622)
			(layers "F.Cu" "F.Mask" "F.Paste")
			(net "P5V_HDD26")
		)
		(pad "P10" smd rect
			(at -9.525 -1.82499 270)
			(size 0.6096 2.3622)
			(layers "F.Cu" "F.Mask" "F.Paste")
			(net "GND")
		)
		(pad "P11" smd rect
			(at -10.795 -1.82499 270)
			(size 0.6096 2.3622)
			(layers "F.Cu" "F.Mask" "F.Paste")
			(net "ACT_HDD_26")
		)
		(pad "P12" smd rect
			(at -12.065 -1.82499 270)
			(size 0.6096 2.3622)
			(layers "F.Cu" "F.Mask" "F.Paste")
			(net "GND")
		)
		(pad "P13" smd rect
			(at -13.335 -1.82499 270)
			(size 0.6096 2.3622)
			(layers "F.Cu" "F.Mask" "F.Paste")
			(net "12V_PRE_26")
		)
		(pad "P14" smd rect
			(at -14.605 -1.82499 270)
			(size 0.6096 2.3622)
			(layers "F.Cu" "F.Mask" "F.Paste")
			(net "P12V_HDD26")
		)
		(pad "P15" smd rect
			(at -15.875 -1.82499 270)
			(size 0.6096 2.3622)
			(layers "F.Cu" "F.Mask" "F.Paste")
			(net "P12V_HDD26")
		)
		(pad "S1" smd rect
			(at 15.875 -1.82499 270)
			(size 0.6096 2.3622)
			(layers "F.Cu" "F.Mask" "F.Paste")
			(net "GND")
		)
		(pad "S2" smd rect
			(at 14.605 -1.82499 270)
			(size 0.6096 2.3622)
			(layers "F.Cu" "F.Mask" "F.Paste")
			(net "SAS_HDD_RX_P26")
		)
		(pad "S3" smd rect
			(at 13.335 -1.82499 270)
			(size 0.6096 2.3622)
			(layers "F.Cu" "F.Mask" "F.Paste")
			(net "SAS_HDD_RX_N26")
		)
		(pad "S4" smd rect
			(at 12.065 -1.82499 270)
			(size 0.6096 2.3622)
			(layers "F.Cu" "F.Mask" "F.Paste")
			(net "GND")
		)
		(pad "S5" smd rect
			(at 10.795 -1.82499 270)
			(size 0.6096 2.3622)
			(layers "F.Cu" "F.Mask" "F.Paste")
			(net "PHY_DRV_A_TO_SCC_A_26_DN")
		)
		(pad "S6" smd rect
			(at 9.525 -1.82499 270)
			(size 0.6096 2.3622)
			(layers "F.Cu" "F.Mask" "F.Paste")
			(net "PHY_DRV_A_TO_SCC_A_26_DP")
		)
		(pad "S7" smd rect
			(at 8.255 -1.82499 270)
			(size 0.6096 2.3622)
			(layers "F.Cu" "F.Mask" "F.Paste")
			(net "GND")
		)
		(pad "S8" smd rect
			(at 7.480046 2.845054 270)
			(size 0.508 2.3622)
			(layers "F.Cu" "F.Mask" "F.Paste")
			(net "GND")
		)
		(pad "S9" smd rect
			(at 6.679946 2.845054 270)
			(size 0.508 2.3622)
			(layers "F.Cu" "F.Mask" "F.Paste")
			(net "Net_464")
		)
		(pad "S10" smd rect
			(at 5.8801 2.845054 270)
			(size 0.508 2.3622)
			(layers "F.Cu" "F.Mask" "F.Paste")
			(net "Net_356")
		)
		(pad "S11" smd rect
			(at 5.08 2.845054 270)
			(size 0.508 2.3622)
			(layers "F.Cu" "F.Mask" "F.Paste")
			(net "GND")
		)
		(pad "S12" smd rect
			(at 4.2799 2.845054 270)
			(size 0.508 2.3622)
			(layers "F.Cu" "F.Mask" "F.Paste")
			(net "Net_392")
		)
		(pad "S13" smd rect
			(at 3.480054 2.845054 270)
			(size 0.508 2.3622)
			(layers "F.Cu" "F.Mask" "F.Paste")
			(net "Net_428")
		)
		(pad "S14" smd rect
			(at 2.679954 2.845054 270)
			(size 0.508 2.3622)
			(layers "F.Cu" "F.Mask" "F.Paste")
			(net "GND")
		)
		(zone
			(layer "F.Cu")
			(hatch none 0.5)
			(connect_pads
				(clearance 0)
			)
			(min_thickness 0.25)
			(keepout
				(tracks not_allowed)
				(vias allowed)
				(pads allowed)
				(copperpour not_allowed)
				(footprints allowed)
			)
			(placement
				(enabled no)
				(sheetname "")
			)
			(fill
				(thermal_gap 0.5)
				(thermal_bridge_width 0.5)
				(island_removal_mode 0)
			)
			(polygon
				(pts
					(xy 94.957646 -74.648568) (xy 87.883746 -74.648568) (xy 87.883746 -81.582768) (xy 88.988646 -81.582768)
					(xy 88.988646 -77.467968) (xy 93.611446 -77.467968) (xy 93.611446 -81.582768) (xy 94.957646 -81.582768)
				)
			)
		)
		(zone
			(layer "F.Cu")
			(hatch none 0.5)
			(connect_pads
				(clearance 0)
			)
			(min_thickness 0.25)
			(keepout
				(tracks allowed)
				(vias not_allowed)
				(pads allowed)
				(copperpour not_allowed)
				(footprints allowed)
			)
			(placement
				(enabled no)
				(sheetname "")
			)
			(fill
				(thermal_gap 0.5)
				(thermal_bridge_width 0.5)
				(island_removal_mode 0)
			)
			(polygon
				(pts
					(xy 94.957646 -74.648568) (xy 87.883746 -74.648568) (xy 87.883746 -81.582768) (xy 88.988646 -81.582768)
					(xy 88.988646 -77.467968) (xy 93.611446 -77.467968) (xy 93.611446 -81.582768) (xy 94.957646 -81.582768)
				)
			)
		)
		(zone
			(layer "F.Cu")
			(hatch none 0.5)
			(connect_pads
				(clearance 0)
			)
			(min_thickness 0.25)
			(keepout
				(tracks not_allowed)
				(vias allowed)
				(pads allowed)
				(copperpour not_allowed)
				(footprints allowed)
			)
			(placement
				(enabled no)
				(sheetname "")
			)
			(fill
				(thermal_gap 0.5)
				(thermal_bridge_width 0.5)
				(island_removal_mode 0)
			)
			(polygon
				(pts
					(xy 94.957646 -41.171368) (xy 87.883746 -41.171368) (xy 87.883746 -34.237168) (xy 88.988646 -34.237168)
					(xy 88.988646 -38.351968) (xy 93.611446 -38.351968) (xy 93.611446 -34.237168) (xy 94.957646 -34.237168)
				)
			)
		)
		(zone
			(layer "F.Cu")
			(hatch none 0.5)
			(connect_pads
				(clearance 0)
			)
			(min_thickness 0.25)
			(keepout
				(tracks allowed)
				(vias not_allowed)
				(pads allowed)
				(copperpour not_allowed)
				(footprints allowed)
			)
			(placement
				(enabled no)
				(sheetname "")
			)
			(fill
				(thermal_gap 0.5)
				(thermal_bridge_width 0.5)
				(island_removal_mode 0)
			)
			(polygon
				(pts
					(xy 94.957646 -41.171368) (xy 87.883746 -41.171368) (xy 87.883746 -34.237168) (xy 88.988646 -34.237168)
					(xy 88.988646 -38.351968) (xy 93.611446 -38.351968) (xy 93.611446 -34.237168) (xy 94.957646 -34.237168)
				)
			)
		)
		(zone
			(layers "F.Cu" "B.Cu" "In1.Cu" "In2.Cu" "In3.Cu" "In4.Cu" "In5.Cu" "In6.Cu"
				"In7.Cu" "In8.Cu" "In9.Cu" "In10.Cu"
			)
			(hatch none 0.5)
			(connect_pads
				(clearance 0)
			)
			(min_thickness 0.25)
			(keepout
				(tracks not_allowed)
				(vias allowed)
				(pads allowed)
				(copperpour not_allowed)
				(footprints allowed)
			)
			(placement
				(enabled no)
				(sheetname "")
			)
			(fill
				(thermal_gap 0.5)
				(thermal_bridge_width 0.5)
				(island_removal_mode 0)
			)
			(polygon
				(pts
					(arc
						(start 92.074746 -39.034974)
						(mid 90.525346 -39.034974)
						(end 92.074746 -39.034974)
					)
				)
			)
		)
		(zone
			(layers "F.Cu" "B.Cu" "In1.Cu" "In2.Cu" "In3.Cu" "In4.Cu" "In5.Cu" "In6.Cu"
				"In7.Cu" "In8.Cu" "In9.Cu" "In10.Cu"
			)
			(hatch none 0.5)
			(connect_pads
				(clearance 0)
			)
			(min_thickness 0.25)
			(keepout
				(tracks not_allowed)
				(vias allowed)
				(pads allowed)
				(copperpour not_allowed)
				(footprints allowed)
			)
			(placement
				(enabled no)
				(sheetname "")
			)
			(fill
				(thermal_gap 0.5)
				(thermal_bridge_width 0.5)
				(island_removal_mode 0)
			)
			(polygon
				(pts
					(arc
						(start 92.277946 -76.784962)
						(mid 90.322146 -76.784962)
						(end 92.277946 -76.784962)
					)
				)
			)
		)
	)
	(footprint ""
		(layer "F.Cu")
		(at 86.121748 -278.580342 90)
		(property "Reference" "R189"
			(at 0 0 90)
			(layer "F.SilkS")
			(hide yes)
			(effects
				(font
					(size 1.27 1.27)
				)
			)
		)
		(property "Value" "4K7R2J-2-GP"
			(at 0.064008 -3.993896 90)
			(unlocked yes)
			(layer "F.Fab")
			(hide yes)
			(effects
				(font
					(size 1.016 1.016)
					(thickness 0.1524)
				)
			)
		)
		(property "Device Type" "R402H16"
			(at 0.064008 -5.517896 90)
			(unlocked yes)
			(layer "F.Fab")
			(hide yes)
			(effects
				(font
					(size 1.016 1.016)
					(thickness 0.1524)
				)
			)
		)
		(duplicate_pad_numbers_are_jumpers no)
		(fp_line
			(start 0.508 -0.9398)
			(end -0.508 -0.9398)
			(stroke
				(width 0.1524)
				(type default)
			)
			(layer "F.SilkS")
		)
		(fp_line
			(start -0.508 -0.9398)
			(end -0.508 0.9398)
			(stroke
				(width 0.1524)
				(type default)
			)
			(layer "F.SilkS")
		)
		(fp_rect
			(start -0.508 0.9398)
			(end 0.508 -0.9398)
			(stroke
				(width 0)
				(type default)
			)
			(fill no)
			(layer "F.CrtYd")
		)
		(fp_rect
			(start -0.508 0.9398)
			(end 0.508 -0.9398)
			(stroke
				(width 0)
				(type default)
			)
			(fill no)
			(layer "F.Fab")
		)
		(pad "1" smd custom
			(at 0 -0.4445 90)
			(size 0.1397 0.1397)
			(layers "F.Cu" "F.Mask" "F.Paste")
			(net "SW_PWR_R_HDD2")
			(options
				(clearance outline)
				(anchor circle)
			)
			(primitives
				(gr_poly
					(pts
						(arc
							(start -0.1778 -0.2794)
							(mid -0.249642 -0.249642)
							(end -0.2794 -0.1778)
						)
						(arc
							(start -0.2794 0.1778)
							(mid -0.249642 0.249642)
							(end -0.1778 0.2794)
						)
						(arc
							(start 0.1778 0.2794)
							(mid 0.249642 0.249642)
							(end 0.2794 0.1778)
						)
						(arc
							(start 0.2794 -0.1778)
							(mid 0.249642 -0.249642)
							(end 0.1778 -0.2794)
						)
					)
					(width 0)
					(fill yes)
				)
			)
		)
		(pad "2" smd custom
			(at 0 0.4445 90)
			(size 0.1397 0.1397)
			(layers "F.Cu" "F.Mask" "F.Paste")
			(net "GND")
			(options
				(clearance outline)
				(anchor circle)
			)
			(primitives
				(gr_poly
					(pts
						(arc
							(start -0.1778 -0.2794)
							(mid -0.249642 -0.249642)
							(end -0.2794 -0.1778)
						)
						(arc
							(start -0.2794 0.1778)
							(mid -0.249642 0.249642)
							(end -0.1778 0.2794)
						)
						(arc
							(start 0.1778 0.2794)
							(mid 0.249642 0.249642)
							(end 0.2794 0.1778)
						)
						(arc
							(start 0.2794 -0.1778)
							(mid 0.249642 -0.249642)
							(end 0.1778 -0.2794)
						)
					)
					(width 0)
					(fill yes)
				)
			)
		)
	)
	(footprint ""
		(layer "F.Cu")
		(at 476.200978 -179.64912)
		(property "Reference" "TP117"
			(at 0 0 0)
			(layer "F.SilkS")
			(hide yes)
			(effects
				(font
					(size 1.27 1.27)
				)
			)
		)
		(property "Value" "TPAD32-GP"
			(at -0.0508 -1.6764 0)
			(unlocked yes)
			(layer "F.Fab")
			(hide yes)
			(effects
				(font
					(size 1.016 1.016)
					(thickness 0.1524)
				)
			)
		)
		(property "Device Type" "TPAD32"
			(at -0.0508 -3.2004 0)
			(unlocked yes)
			(layer "F.Fab")
			(hide yes)
			(effects
				(font
					(size 1.016 1.016)
					(thickness 0.1524)
				)
			)
		)
		(duplicate_pad_numbers_are_jumpers no)
		(fp_poly
			(pts
				(arc
					(start 0.4064 0)
					(mid -0.4064 0)
					(end 0.4064 0)
				)
			)
			(stroke
				(width 0)
				(type default)
			)
			(fill no)
			(layer "F.CrtYd")
		)
		(fp_poly
			(pts
				(arc
					(start 0.7112 0)
					(mid -0.7112 0)
					(end 0.7112 0)
				)
			)
			(stroke
				(width 0)
				(type default)
			)
			(fill no)
			(layer "F.Fab")
		)
		(pad "1" smd circle
			(at 0 0)
			(size 0.8128 0.8128)
			(layers "F.Cu" "F.Mask" "F.Paste")
			(net "ACT_HDD_23")
		)
	)
	(footprint ""
		(layer "F.Cu")
		(at 160.608264 -304.310796 180)
		(property "Reference" "R257"
			(at 0 0 180)
			(layer "F.SilkS")
			(hide yes)
			(effects
				(font
					(size 1.27 1.27)
				)
			)
		)
		(property "Value" "91R3F-1-GP"
			(at -0.0254 -2.5146 180)
			(unlocked yes)
			(layer "F.Fab")
			(hide yes)
			(effects
				(font
					(size 1.016 1.016)
					(thickness 0.1524)
				)
			)
		)
		(property "Device Type" "R603H22"
			(at -0.0254 -4.0386 180)
			(unlocked yes)
			(layer "F.Fab")
			(hide yes)
			(effects
				(font
					(size 1.016 1.016)
					(thickness 0.1524)
				)
			)
		)
		(duplicate_pad_numbers_are_jumpers no)
		(fp_line
			(start 0.2032 0)
			(end 0.4826 0)
			(stroke
				(width 0.2032)
				(type default)
			)
			(layer "F.SilkS")
		)
		(fp_line
			(start -0.4826 0)
			(end -0.2032 0)
			(stroke
				(width 0.2032)
				(type default)
			)
			(layer "F.SilkS")
		)
		(fp_rect
			(start -0.5842 1.3335)
			(end 0.5842 -1.3335)
			(stroke
				(width 0)
				(type default)
			)
			(fill no)
			(layer "F.CrtYd")
		)
		(fp_rect
			(start -0.5842 1.3335)
			(end 0.5842 -1.3335)
			(stroke
				(width 0)
				(type default)
			)
			(fill no)
			(layer "F.Fab")
		)
		(pad "1" smd custom
			(at 0 -0.762 180)
			(size 0.2159 0.2159)
			(layers "F.Cu" "F.Mask" "F.Paste")
			(net "P5V_B")
			(options
				(clearance outline)
				(anchor circle)
			)
			(primitives
				(gr_poly
					(pts
						(arc
							(start -0.3302 -0.4318)
							(mid -0.402042 -0.402042)
							(end -0.4318 -0.3302)
						)
						(arc
							(start -0.4318 0.3302)
							(mid -0.402042 0.402042)
							(end -0.3302 0.4318)
						)
						(arc
							(start 0.3302 0.4318)
							(mid 0.402042 0.402042)
							(end 0.4318 0.3302)
						)
						(arc
							(start 0.4318 -0.3302)
							(mid 0.402042 -0.402042)
							(end 0.3302 -0.4318)
						)
					)
					(width 0)
					(fill yes)
				)
			)
		)
		(pad "2" smd custom
			(at 0 0.762 180)
			(size 0.2159 0.2159)
			(layers "F.Cu" "F.Mask" "F.Paste")
			(net "DRV_ACT_29")
			(options
				(clearance outline)
				(anchor circle)
			)
			(primitives
				(gr_poly
					(pts
						(arc
							(start -0.3302 -0.4318)
							(mid -0.402042 -0.402042)
							(end -0.4318 -0.3302)
						)
						(arc
							(start -0.4318 0.3302)
							(mid -0.402042 0.402042)
							(end -0.3302 0.4318)
						)
						(arc
							(start 0.3302 0.4318)
							(mid 0.402042 0.402042)
							(end 0.4318 0.3302)
						)
						(arc
							(start 0.4318 -0.3302)
							(mid 0.402042 -0.402042)
							(end 0.3302 -0.4318)
						)
					)
					(width 0)
					(fill yes)
				)
			)
		)
	)
)
